# T6G (Grand Teton) — schematic netlist excerpt (pin names and nets, part order shuffled) for the footprints in the layout excerpt that follows; sources: Cadence DE-HDL packaged netlist, KiCad conversion of 04192023_DAF0TMB3IC0_F0TG_MB_C_brd_V02_OCP.brd

PC146_8  Q_CAP  0.1UF 25V 10% X7R  pkg 0402  page 205 : A = PVDDCR_CPU1_P0_VCCS ; B = GND
PC183  Q_CAP  0.22UF 16V 10% X7R  pkg 0402  page 206 : A = SW_PVDDIO_P0_BOOT4_R ; B = SW_PVDDIO_P0_BOOTR4

(kicad_pcb
	(version 20260206)
	(generator "pcbnew")
	(generator_version "10.0")
	(general
		(thickness 1.6)
		(legacy_teardrops no)
	)
	(paper "A4")
	(title_block
		(title "04192023_DAF0TMB3IC0_F0TG_MB_C_brd_V02_OCP.brd")
		(comment 1 "Grand Teton / footprints 3650-3651 of 8354")
	)
	(layers
		(0 "F.Cu" signal "TOP")
		(4 "In1.Cu" signal "GND")
		(6 "In2.Cu" signal "IN1")
		(8 "In3.Cu" signal "GND1")
		(10 "In4.Cu" signal "IN2")
		(12 "In5.Cu" signal "GND2")
		(14 "In6.Cu" signal "IN3")
		(16 "In7.Cu" signal "GND3")
		(18 "In8.Cu" signal "VCC")
		(20 "In9.Cu" signal "VCC1")
		(22 "In10.Cu" signal "GND4")
		(24 "In11.Cu" signal "IN4")
		(26 "In12.Cu" signal "GND5")
		(28 "In13.Cu" signal "IN5")
		(30 "In14.Cu" signal "GND6")
		(32 "In15.Cu" signal "IN6")
		(34 "In16.Cu" signal "GND7")
		(2 "B.Cu" signal "BOTTOM")
		(9 "F.Adhes" user "F.Adhesive")
		(11 "B.Adhes" user "B.Adhesive")
		(13 "F.Paste" user "Package Geometry/Pastemask Top")
		(15 "B.Paste" user "Package Geometry/Pastemask Bottom")
		(5 "F.SilkS" user "Ref Des/Silkscreen Top")
		(7 "B.SilkS" user "Ref Des/Silkscreen Bottom")
		(1 "F.Mask" user "Board Geometry/Soldermask Top")
		(3 "B.Mask" user "Board Geometry/Soldermask Bottom")
		(17 "Dwgs.User" user "User.Drawings")
		(19 "Cmts.User" user "User.Comments")
		(21 "Eco1.User" user "User.Eco1")
		(23 "Eco2.User" user "User.Eco2")
		(25 "Edge.Cuts" user "Board Geometry/Outline")
		(27 "Margin" user)
		(31 "F.CrtYd" user "Package Geometry/Place Bound Top")
		(29 "B.CrtYd" user "Package Geometry/Place Bound Bottom")
		(35 "F.Fab" user "Ref Des/Assembly Top")
		(33 "B.Fab" user "Ref Des/Assembly Bottom")
	)
	(footprint ""
		(layer "F.Cu")
		(at 277.20798 -351.368106 -90)
		(property "Reference" "PC183"
			(at 0 0 270)
			(layer "F.SilkS")
			(hide yes)
			(effects
				(font
					(size 1.27 1.27)
				)
			)
		)
		(property "Value" ""
			(at 0 0 270)
			(layer "F.Fab")
			(effects
				(font
					(size 1.27 1.27)
				)
			)
		)
		(duplicate_pad_numbers_are_jumpers no)
		(fp_line
			(start -0.7874 0.4064)
			(end -0.7874 -0.4064)
			(stroke
				(width 0.1524)
				(type default)
			)
			(layer "F.SilkS")
		)
		(fp_line
			(start 0.7874 0.4064)
			(end -0.7874 0.4064)
			(stroke
				(width 0.1524)
				(type default)
			)
			(layer "F.SilkS")
		)
		(fp_line
			(start -0.7874 -0.4064)
			(end 0.7874 -0.4064)
			(stroke
				(width 0.1524)
				(type default)
			)
			(layer "F.SilkS")
		)
		(fp_line
			(start 0.7874 -0.4064)
			(end 0.7874 0.4064)
			(stroke
				(width 0.1524)
				(type default)
			)
			(layer "F.SilkS")
		)
		(fp_line
			(start -0.67945 0.3048)
			(end -0.67945 -0.305054)
			(stroke
				(width 0.1)
				(type default)
			)
			(layer "F.Fab")
		)
		(fp_line
			(start -0.12065 0.3048)
			(end -0.67945 0.3048)
			(stroke
				(width 0.1)
				(type default)
			)
			(layer "F.Fab")
		)
		(fp_line
			(start 0.120396 0.3048)
			(end 0.120396 0.2794)
			(stroke
				(width 0.1)
				(type default)
			)
			(layer "F.Fab")
		)
		(fp_line
			(start 0.67945 0.3048)
			(end 0.120396 0.3048)
			(stroke
				(width 0.1)
				(type default)
			)
			(layer "F.Fab")
		)
		(fp_line
			(start -0.12065 0.2794)
			(end -0.12065 0.3048)
			(stroke
				(width 0.1)
				(type default)
			)
			(layer "F.Fab")
		)
		(fp_line
			(start 0.120396 0.2794)
			(end -0.12065 0.2794)
			(stroke
				(width 0.1)
				(type default)
			)
			(layer "F.Fab")
		)
		(fp_line
			(start -0.12065 -0.2794)
			(end 0.12065 -0.2794)
			(stroke
				(width 0.1)
				(type default)
			)
			(layer "F.Fab")
		)
		(fp_line
			(start 0.12065 -0.2794)
			(end 0.12065 -0.3048)
			(stroke
				(width 0.1)
				(type default)
			)
			(layer "F.Fab")
		)
		(fp_line
			(start 0.12065 -0.3048)
			(end 0.67945 -0.3048)
			(stroke
				(width 0.1)
				(type default)
			)
			(layer "F.Fab")
		)
		(fp_line
			(start 0.67945 -0.3048)
			(end 0.67945 0.3048)
			(stroke
				(width 0.1)
				(type default)
			)
			(layer "F.Fab")
		)
		(fp_line
			(start -0.67945 -0.305054)
			(end -0.12065 -0.305054)
			(stroke
				(width 0.1)
				(type default)
			)
			(layer "F.Fab")
		)
		(fp_line
			(start -0.12065 -0.305054)
			(end -0.12065 -0.2794)
			(stroke
				(width 0.1)
				(type default)
			)
			(layer "F.Fab")
		)
		(pad "1" smd circle
			(at -0.40005 0 270)
			(size 0 0)
			(layers "F.Cu" "F.Mask" "F.Paste")
			(net "SW_PVDDIO_P0_BOOT4_R")
		)
		(pad "2" smd circle
			(at 0.40005 0 270)
			(size 0 0)
			(layers "F.Cu" "F.Mask" "F.Paste")
			(net "SW_PVDDIO_P0_BOOTR4")
		)
	)
	(footprint ""
		(layer "F.Cu")
		(at 289.314382 -351.573846 90)
		(property "Reference" "PC146_8"
			(at 0 0 90)
			(layer "F.SilkS")
			(hide yes)
			(effects
				(font
					(size 1.27 1.27)
				)
			)
		)
		(property "Value" ""
			(at 0 0 90)
			(layer "F.Fab")
			(effects
				(font
					(size 1.27 1.27)
				)
			)
		)
		(duplicate_pad_numbers_are_jumpers no)
		(fp_line
			(start 0.7874 -0.4064)
			(end 0.7874 0.4064)
			(stroke
				(width 0.1524)
				(type default)
			)
			(layer "F.SilkS")
		)
		(fp_line
			(start -0.7874 -0.4064)
			(end 0.7874 -0.4064)
			(stroke
				(width 0.1524)
				(type default)
			)
			(layer "F.SilkS")
		)
		(fp_line
			(start 0.7874 0.4064)
			(end -0.7874 0.4064)
			(stroke
				(width 0.1524)
				(type default)
			)
			(layer "F.SilkS")
		)
		(fp_line
			(start -0.7874 0.4064)
			(end -0.7874 -0.4064)
			(stroke
				(width 0.1524)
				(type default)
			)
			(layer "F.SilkS")
		)
		(fp_line
			(start -0.12065 -0.305054)
			(end -0.12065 -0.2794)
			(stroke
				(width 0.1)
				(type default)
			)
			(layer "F.Fab")
		)
		(fp_line
			(start -0.67945 -0.305054)
			(end -0.12065 -0.305054)
			(stroke
				(width 0.1)
				(type default)
			)
			(layer "F.Fab")
		)
		(fp_line
			(start 0.67945 -0.3048)
			(end 0.67945 0.3048)
			(stroke
				(width 0.1)
				(type default)
			)
			(layer "F.Fab")
		)
		(fp_line
			(start 0.12065 -0.3048)
			(end 0.67945 -0.3048)
			(stroke
				(width 0.1)
				(type default)
			)
			(layer "F.Fab")
		)
		(fp_line
			(start 0.12065 -0.2794)
			(end 0.12065 -0.3048)
			(stroke
				(width 0.1)
				(type default)
			)
			(layer "F.Fab")
		)
		(fp_line
			(start -0.12065 -0.2794)
			(end 0.12065 -0.2794)
			(stroke
				(width 0.1)
				(type default)
			)
			(layer "F.Fab")
		)
		(fp_line
			(start 0.120396 0.2794)
			(end -0.12065 0.2794)
			(stroke
				(width 0.1)
				(type default)
			)
			(layer "F.Fab")
		)
		(fp_line
			(start -0.12065 0.2794)
			(end -0.12065 0.3048)
			(stroke
				(width 0.1)
				(type default)
			)
			(layer "F.Fab")
		)
		(fp_line
			(start 0.67945 0.3048)
			(end 0.120396 0.3048)
			(stroke
				(width 0.1)
				(type default)
			)
			(layer "F.Fab")
		)
		(fp_line
			(start 0.120396 0.3048)
			(end 0.120396 0.2794)
			(stroke
				(width 0.1)
				(type default)
			)
			(layer "F.Fab")
		)
		(fp_line
			(start -0.12065 0.3048)
			(end -0.67945 0.3048)
			(stroke
				(width 0.1)
				(type default)
			)
			(layer "F.Fab")
		)
		(fp_line
			(start -0.67945 0.3048)
			(end -0.67945 -0.305054)
			(stroke
				(width 0.1)
				(type default)
			)
			(layer "F.Fab")
		)
		(pad "1" smd circle
			(at -0.40005 0 90)
			(size 0 0)
			(layers "F.Cu" "F.Mask" "F.Paste")
			(net "PVDDCR_CPU1_P0_VCCS")
		)
		(pad "2" smd circle
			(at 0.40005 0 90)
			(size 0 0)
			(layers "F.Cu" "F.Mask" "F.Paste")
			(net "GND")
		)
	)
)
